(kicad_pcb
	(version 20221018)
	(generator pcbnew)
	(general
    (thickness 1.62)
  )
	(paper "A4")
	(title_block
    (title "ECP5 - Datacenter Secure Control Module (DC-SCM)")
    (date "2024-07-01")
    (rev "1.2.1")
		(comment 9 "footprints 158-163 of 506")
	)
	(layers
    (0 "F.Cu" signal)
    (1 "In1.Cu" power)
    (2 "In2.Cu" signal)
    (3 "In3.Cu" power)
    (4 "In4.Cu" power)
    (5 "In5.Cu" signal)
    (6 "In6.Cu" power)
    (31 "B.Cu" signal)
    (32 "B.Adhes" user "B.Adhesive")
    (33 "F.Adhes" user "F.Adhesive")
    (34 "B.Paste" user)
    (35 "F.Paste" user)
    (36 "B.SilkS" user "B.Silkscreen")
    (37 "F.SilkS" user "F.Silkscreen")
    (38 "B.Mask" user)
    (39 "F.Mask" user)
    (40 "Dwgs.User" user "User.Drawings")
    (41 "Cmts.User" user "User.Comments")
    (42 "Eco1.User" user "User.Eco1")
    (43 "Eco2.User" user "User.Eco2")
    (44 "Edge.Cuts" user)
    (45 "Margin" user)
    (46 "B.CrtYd" user "B.Courtyard")
    (47 "F.CrtYd" user "F.Courtyard")
    (48 "B.Fab" user)
    (49 "F.Fab" user)
  )
	(footprint "antmicro-footprints:C_0402_1005Metric" (layer "F.Cu")
    (at 128.24 133.74 -90)
    (descr "Capacitor SMD 0402")
    (tags "capacitor SMD 0402")
    (property "Author" "Antmicro")
    (property "Dielectric" "X7R")
    (property "License" "Apache-2.0")
    (property "MPN" "GRM155R71H103KA88D")
    (property "Manufacturer" "Murata")
    (property "Public" "False")
    (property "Sheetfile" "interfaces.kicad_sch")
    (property "Sheetname" "Interfaces")
    (property "Val" "10n")
    (property "Voltage" "50V")
    (property "ki_description" "SMD Multilayer Ceramic Capacitor, 10000 pF, 50 V, 0402 [1005 Metric], ± 10%, X7R, GRM Series")
    (property "ki_keywords" "0402, SMT, CAPACITOR, PASSIVE")
    (attr smd)
    (fp_text reference "C56" (at -0.015 -1.01 90) (layer "F.SilkS")
        (effects (font (size 0.7 0.7) (thickness 0.127)))
    )
    (fp_text value "C_10n_0402" (at 0 1.17 90) (layer "F.Fab")
        (effects (font (size 1 1) (thickness 0.15)))
    )
    (fp_text user "License: Apache-2.0" (at -0.939 5.799 -90) (layer "F.Fab") hide
        (effects (font (size 0.7 0.7) (thickness 0.15)) (justify left bottom))
    )
    (fp_text user "Author: Antmicro" (at -0.939 3.399 -90) (layer "F.Fab") hide
        (effects (font (size 0.7 0.7) (thickness 0.15)) (justify left bottom))
    )
    (fp_text user "${REFERENCE}" (at 0 0 90) (layer "F.Fab")
        (effects (font (size 0.25 0.25) (thickness 0.04)))
    )
    (fp_rect (start -0.925 -0.47) (end 0.925 0.47)
      (stroke (width 0.05) (type default)) (fill none) (layer "F.CrtYd"))
    (fp_line (start -0.494 -0.25) (end 0.504 -0.25)
      (stroke (width 0.15) (type solid)) (layer "F.Fab"))
    (fp_line (start -0.494 0.248) (end -0.494 -0.25)
      (stroke (width 0.15) (type solid)) (layer "F.Fab"))
    (fp_line (start 0.504 -0.25) (end 0.504 0.248)
      (stroke (width 0.15) (type solid)) (layer "F.Fab"))
    (fp_line (start 0.504 0.248) (end -0.494 0.248)
      (stroke (width 0.15) (type solid)) (layer "F.Fab"))
    (pad "1" smd roundrect (at -0.48 0 270) (size 0.59 0.64) (layers "F.Cu" "F.Paste" "F.Mask") (roundrect_rratio 0.25)
      (net 1 "GND") (pintype "passive"))
    (pad "2" smd roundrect (at 0.48 0 270) (size 0.59 0.64) (layers "F.Cu" "F.Paste" "F.Mask") (roundrect_rratio 0.25)
      (net 2 "VCC3V3") (pintype "passive"))
  )
	(footprint "antmicro-footprints:QFN-32-1EP_5x5mm" (layer "F.Cu")
    (at 124.955 126.61 180)
    (property "Author" "Antmicro")
    (property "License" "Apache-2.0")
    (property "MPN" "USB3300-EZK-TR")
    (property "Manufacturer" "Microchip Technology")
    (property "Sheetfile" "interfaces.kicad_sch")
    (property "Sheetname" "Interfaces")
    (property "ki_description" "USB Interface, USB Host Controller, USB 2.0 OTG, 3 V, 3.6 V, VQFN, 32 Pins")
    (property "ki_keywords" "SMT, INTERFACE, CONTROLLER, IC, USB")
    (attr smd)
    (fp_text reference "U8" (at -2.445 3.61 180) (layer "F.SilkS")
        (effects (font (size 0.7 0.7) (thickness 0.12051)))
    )
    (fp_text value "USB3300-EZK-TR" (at 3.23987 3.520501 180) (layer "F.Fab")
        (effects (font (size 0.482094 0.482094) (thickness 0.015)))
    )
    (fp_text user "License: Apache-2.0" (at -4.939 5.91 180) (layer "F.Fab") hide
        (effects (font (size 0.7 0.7) (thickness 0.15)) (justify left bottom))
    )
    (fp_text user "Author: Antmicro" (at -4.939 8.31 180) (layer "F.Fab") hide
        (effects (font (size 0.7 0.7) (thickness 0.15)) (justify left bottom))
    )
    (fp_text user "${REFERENCE}" (at -4.939 7.11 180) (layer "F.Fab") hide
        (effects (font (size 0.7 0.7) (thickness 0.15)) (justify left bottom))
    )
    (fp_rect (start -1.446 -0.175) (end -0.246 -1.375)
      (stroke (width 0.2) (type solid)) (fill solid) (layer "F.Paste"))
    (fp_rect (start -1.446 1.474) (end -0.246 0.274)
      (stroke (width 0.2) (type solid)) (fill solid) (layer "F.Paste"))
    (fp_rect (start 0.203 -0.175) (end 1.403 -1.375)
      (stroke (width 0.2) (type solid)) (fill solid) (layer "F.Paste"))
    (fp_rect (start 0.203 1.474) (end 1.403 0.274)
      (stroke (width 0.2) (type solid)) (fill solid) (layer "F.Paste"))
    (fp_line (start -2.62 2.648) (end -2.62 2.249)
      (stroke (width 0.15) (type solid)) (layer "F.SilkS"))
    (fp_line (start -2.221 -2.551) (end -2.62 -2.149)
      (stroke (width 0.15) (type solid)) (layer "F.SilkS"))
    (fp_line (start -2.221 2.648) (end -2.62 2.648)
      (stroke (width 0.15) (type solid)) (layer "F.SilkS"))
    (fp_line (start 2.581 -2.551) (end 2.178 -2.551)
      (stroke (width 0.15) (type solid)) (layer "F.SilkS"))
    (fp_line (start 2.581 -2.551) (end 2.581 -2.149)
      (stroke (width 0.15) (type solid)) (layer "F.SilkS"))
    (fp_line (start 2.581 2.249) (end 2.581 2.648)
      (stroke (width 0.15) (type solid)) (layer "F.SilkS"))
    (fp_line (start 2.581 2.648) (end 2.178 2.648)
      (stroke (width 0.15) (type solid)) (layer "F.SilkS"))
    (fp_circle (center -3.25 -1.702) (end -3.2 -1.702)
      (stroke (width 0.15) (type solid)) (fill solid) (layer "F.SilkS"))
    (fp_rect (start -2.74 -2.75) (end 2.75 2.74)
      (stroke (width 0.05) (type solid)) (fill none) (layer "F.CrtYd"))
    (fp_line (start -2.499 -2.299) (end -2.298 -2.5)
      (stroke (width 0.15) (type solid)) (layer "F.Fab"))
    (fp_rect (start -2.499 -2.5) (end 2.5 2.499)
      (stroke (width 0.15) (type solid)) (fill none) (layer "F.Fab"))
    (pad "1" smd rect (at -2.495 -1.702 90) (size 0.28 0.85) (layers "F.Cu" "F.Paste" "F.Mask")
      (net 1 "GND") (pinfunction "GND") (pintype "power_in") (solder_mask_margin 0.07))
    (pad "2" smd rect (at -2.495 -1.2 90) (size 0.28 0.85) (layers "F.Cu" "F.Paste" "F.Mask")
      (net 1 "GND") (pinfunction "GND") (pintype "passive") (solder_mask_margin 0.07))
    (pad "3" smd rect (at -2.495 -0.701 90) (size 0.28 0.85) (layers "F.Cu" "F.Paste" "F.Mask")
      (net 496 "unconnected-(U8-CPEN-Pad3)") (pinfunction "CPEN") (pintype "output+no_connect") (solder_mask_margin 0.07))
    (pad "4" smd rect (at -2.495 -0.201 90) (size 0.28 0.85) (layers "F.Cu" "F.Paste" "F.Mask")
      (net 404 "Net-(U8-VBUS)") (pinfunction "VBUS") (pintype "bidirectional") (solder_mask_margin 0.07))
    (pad "5" smd rect (at -2.495 0.296 90) (size 0.28 0.85) (layers "F.Cu" "F.Paste" "F.Mask")
      (net 497 "unconnected-(U8-ID-Pad5)") (pinfunction "ID") (pintype "input+no_connect") (solder_mask_margin 0.07))
    (pad "6" smd rect (at -2.495 0.8 90) (size 0.28 0.85) (layers "F.Cu" "F.Paste" "F.Mask")
      (net 2 "VCC3V3") (pinfunction "VDD3.3") (pintype "power_in") (solder_mask_margin 0.07))
    (pad "7" smd rect (at -2.495 1.3 90) (size 0.28 0.85) (layers "F.Cu" "F.Paste" "F.Mask")
      (net 98 "USB2_DP") (pinfunction "DP") (pintype "bidirectional") (solder_mask_margin 0.07))
    (pad "8" smd rect (at -2.495 1.8 90) (size 0.28 0.85) (layers "F.Cu" "F.Paste" "F.Mask")
      (net 99 "USB2_DN") (pinfunction "DM") (pintype "bidirectional") (solder_mask_margin 0.07))
    (pad "9" smd rect (at -1.768 2.523 90) (size 0.85 0.28) (layers "F.Cu" "F.Paste" "F.Mask")
      (net 317 "ULPI2_RESET") (pinfunction "RESET") (pintype "input") (solder_mask_margin 0.07))
    (pad "10" smd rect (at -1.269 2.523 90) (size 0.85 0.28) (layers "F.Cu" "F.Paste" "F.Mask")
      (net 498 "unconnected-(U8-EXTVBUS-Pad10)") (pinfunction "EXTVBUS") (pintype "input+no_connect") (solder_mask_margin 0.07))
    (pad "11" smd rect (at -0.772 2.523 90) (size 0.85 0.28) (layers "F.Cu" "F.Paste" "F.Mask")
      (net 318 "ULPI2_NXT") (pinfunction "NXT") (pintype "output") (solder_mask_margin 0.07))
    (pad "12" smd rect (at -0.272 2.523 90) (size 0.85 0.28) (layers "F.Cu" "F.Paste" "F.Mask")
      (net 319 "ULPI_DIR") (pinfunction "DIR") (pintype "output") (solder_mask_margin 0.07))
    (pad "13" smd rect (at 0.229 2.523 90) (size 0.85 0.28) (layers "F.Cu" "F.Paste" "F.Mask")
      (net 320 "ULPI2_STP") (pinfunction "STP") (pintype "input") (solder_mask_margin 0.07))
    (pad "14" smd rect (at 0.728 2.523 90) (size 0.85 0.28) (layers "F.Cu" "F.Paste" "F.Mask")
      (net 321 "ULPI2_CLKO") (pinfunction "CLKOUT") (pintype "output") (solder_mask_margin 0.07))
    (pad "15" smd rect (at 1.23 2.523 90) (size 0.85 0.28) (layers "F.Cu" "F.Paste" "F.Mask")
      (net 227 "Net-(C71-Pad1)") (pinfunction "VDD1.8") (pintype "power_in") (solder_mask_margin 0.07))
    (pad "16" smd rect (at 1.73 2.523 90) (size 0.85 0.28) (layers "F.Cu" "F.Paste" "F.Mask")
      (net 2 "VCC3V3") (pinfunction "VDD3.3") (pintype "passive") (solder_mask_margin 0.07))
    (pad "17" smd rect (at 2.456 1.8 90) (size 0.28 0.85) (layers "F.Cu" "F.Paste" "F.Mask")
      (net 322 "ULPI2_D7") (pinfunction "DATA[7]") (pintype "bidirectional") (solder_mask_margin 0.07))
    (pad "18" smd rect (at 2.456 1.3 90) (size 0.28 0.85) (layers "F.Cu" "F.Paste" "F.Mask")
      (net 323 "ULPI2_D6") (pinfunction "DATA[6]") (pintype "bidirectional") (solder_mask_margin 0.07))
    (pad "19" smd rect (at 2.456 0.8 90) (size 0.28 0.85) (layers "F.Cu" "F.Paste" "F.Mask")
      (net 324 "ULPI2_D5") (pinfunction "DATA[5]") (pintype "bidirectional") (solder_mask_margin 0.07))
    (pad "20" smd rect (at 2.456 0.296 90) (size 0.28 0.85) (layers "F.Cu" "F.Paste" "F.Mask")
      (net 325 "ULPI2_D4") (pinfunction "DATA[4]") (pintype "bidirectional") (solder_mask_margin 0.07))
    (pad "21" smd rect (at 2.456 -0.201 90) (size 0.28 0.85) (layers "F.Cu" "F.Paste" "F.Mask")
      (net 326 "ULPI2_D3") (pinfunction "DATA[3]") (pintype "bidirectional") (solder_mask_margin 0.07))
    (pad "22" smd rect (at 2.456 -0.701 90) (size 0.28 0.85) (layers "F.Cu" "F.Paste" "F.Mask")
      (net 327 "ULPI2_D2") (pinfunction "DATA[2]") (pintype "bidirectional") (solder_mask_margin 0.07))
    (pad "23" smd rect (at 2.456 -1.2 90) (size 0.28 0.85) (layers "F.Cu" "F.Paste" "F.Mask")
      (net 328 "ULPI2_D1") (pinfunction "DATA[1]") (pintype "bidirectional") (solder_mask_margin 0.07))
    (pad "24" smd rect (at 2.456 -1.702 90) (size 0.28 0.85) (layers "F.Cu" "F.Paste" "F.Mask")
      (net 329 "ULPI2_D0") (pinfunction "DATA[0]") (pintype "bidirectional") (solder_mask_margin 0.07))
    (pad "25" smd rect (at 1.73 -2.426 90) (size 0.85 0.28) (layers "F.Cu" "F.Paste" "F.Mask")
      (net 2 "VCC3V3") (pinfunction "VDD3.3") (pintype "passive") (solder_mask_margin 0.07))
    (pad "26" smd rect (at 1.23 -2.426 90) (size 0.85 0.28) (layers "F.Cu" "F.Paste" "F.Mask")
      (net 227 "Net-(C71-Pad1)") (pinfunction "VDD1.8") (pintype "passive") (solder_mask_margin 0.07))
    (pad "27" smd rect (at 0.728 -2.426 90) (size 0.85 0.28) (layers "F.Cu" "F.Paste" "F.Mask")
      (net 499 "unconnected-(U8-XO-Pad27)") (pinfunction "XO") (pintype "output+no_connect") (solder_mask_margin 0.07))
    (pad "28" smd rect (at 0.229 -2.426 90) (size 0.85 0.28) (layers "F.Cu" "F.Paste" "F.Mask")
      (net 678 "/Interfaces/USB2_CLK") (pinfunction "XI") (pintype "input") (solder_mask_margin 0.07))
    (pad "29" smd rect (at -0.272 -2.426 90) (size 0.85 0.28) (layers "F.Cu" "F.Paste" "F.Mask")
      (net 221 "Net-(U8-VDDA1.8)") (pinfunction "VDDA1.8") (pintype "power_in") (solder_mask_margin 0.07))
    (pad "30" smd rect (at -0.772 -2.426 90) (size 0.85 0.28) (layers "F.Cu" "F.Paste" "F.Mask")
      (net 2 "VCC3V3") (pinfunction "VDD3.3") (pintype "passive") (solder_mask_margin 0.07))
    (pad "31" smd rect (at -1.269 -2.426 90) (size 0.85 0.28) (layers "F.Cu" "F.Paste" "F.Mask")
      (net 2 "VCC3V3") (pinfunction "REG_EN") (pintype "bidirectional") (solder_mask_margin 0.07))
    (pad "32" smd rect (at -1.768 -2.426 90) (size 0.85 0.28) (layers "F.Cu" "F.Paste" "F.Mask")
      (net 405 "Net-(U8-RBIAS)") (pinfunction "RBIAS") (pintype "bidirectional") (solder_mask_margin 0.07))
    (pad "33" smd rect (at -0.02 0.048 90) (size 3.45 3.45) (layers "F.Cu" "F.Mask")
      (net 1 "GND") (pinfunction "EP") (pintype "passive"))
  )
	(footprint "antmicro-footprints:TP_SMD_1mm" (layer "F.Cu")
    (at 115.270001 158.864201 180)
    (property "Author" "Antmicro")
    (property "License" "Apache-2.0")
    (property "MPN" "")
    (property "Manufacturer" "")
    (property "Sheetfile" "pcie-conn.kicad_sch")
    (property "Sheetname" "PCIe-connector")
    (property "exclude_from_bom" "")
    (property "ki_description" "Test point 1mm SMD")
    (property "ki_keywords" "TESTPOINT")
    (attr exclude_from_pos_files exclude_from_bom)
    (fp_text reference "TP2" (at 2.640001 -0.4158 180) (layer "F.SilkS")
        (effects (font (size 0.7 0.7) (thickness 0.15)) (justify left bottom))
    )
    (fp_text value "TP_1mm_SMD" (at 0 1.4 180) (layer "F.Fab")
        (effects (font (size 0.7 0.7) (thickness 0.15)) (justify left bottom))
    )
    (fp_text user "Author: Antmicro" (at -0.5 4 180) (layer "F.Fab") hide
        (effects (font (size 0.7 0.7) (thickness 0.15)) (justify left bottom))
    )
    (fp_text user "${REFERENCE}" (at -0.5 2.8 180) (layer "F.Fab") hide
        (effects (font (size 0.7 0.7) (thickness 0.15)) (justify left bottom))
    )
    (fp_text user "License: Apache-2.0" (at -0.5 5.2 180) (layer "F.Fab") hide
        (effects (font (size 0.7 0.7) (thickness 0.15)) (justify left bottom))
    )
    (fp_circle (center 0 0) (end 0.6 0)
      (stroke (width 0.05) (type default)) (fill none) (layer "F.CrtYd"))
    (pad "1" smd circle (at 0 0 180) (size 1 1) (layers "F.Cu" "F.Mask")
      (net 380 "Net-(J2-~{CLKREQ})") (pinfunction "1") (pintype "passive"))
  )
	(footprint "antmicro-footprints:TP_SMD_1mm" (layer "F.Cu")
    (at 115.270001 160.806701 180)
    (property "Author" "Antmicro")
    (property "License" "Apache-2.0")
    (property "MPN" "")
    (property "Manufacturer" "")
    (property "Sheetfile" "pcie-conn.kicad_sch")
    (property "Sheetname" "PCIe-connector")
    (property "exclude_from_bom" "")
    (property "ki_description" "Test point 1mm SMD")
    (property "ki_keywords" "TESTPOINT")
    (attr exclude_from_pos_files exclude_from_bom)
    (fp_text reference "TP3" (at 2.640001 -0.4158 180) (layer "F.SilkS")
        (effects (font (size 0.7 0.7) (thickness 0.15)) (justify left bottom))
    )
    (fp_text value "TP_1mm_SMD" (at 0 1.4 180) (layer "F.Fab")
        (effects (font (size 0.7 0.7) (thickness 0.15)) (justify left bottom))
    )
    (fp_text user "License: Apache-2.0" (at -0.5 5.2 180) (layer "F.Fab") hide
        (effects (font (size 0.7 0.7) (thickness 0.15)) (justify left bottom))
    )
    (fp_text user "${REFERENCE}" (at -0.5 2.8 180) (layer "F.Fab") hide
        (effects (font (size 0.7 0.7) (thickness 0.15)) (justify left bottom))
    )
    (fp_text user "Author: Antmicro" (at -0.5 4 180) (layer "F.Fab") hide
        (effects (font (size 0.7 0.7) (thickness 0.15)) (justify left bottom))
    )
    (fp_circle (center 0 0) (end 0.6 0)
      (stroke (width 0.05) (type default)) (fill none) (layer "F.CrtYd"))
    (pad "1" smd circle (at 0 0 180) (size 1 1) (layers "F.Cu" "F.Mask")
      (net 58 "PRSNT0_N") (pinfunction "1") (pintype "passive"))
  )
	(footprint "antmicro-footprints:TP_SMD_1mm" (layer "F.Cu")
    (at 86.1 69.6008)
    (property "Author" "Antmicro")
    (property "License" "Apache-2.0")
    (property "MPN" "")
    (property "Manufacturer" "")
    (property "Sheetfile" "power-supply.kicad_sch")
    (property "Sheetname" "Power supply")
    (property "exclude_from_bom" "")
    (property "ki_description" "Test point 1mm SMD")
    (property "ki_keywords" "TESTPOINT")
    (attr exclude_from_pos_files exclude_from_bom)
    (fp_text reference "TP6" (at -0.91 1.7742 180) (layer "F.SilkS")
        (effects (font (size 0.7 0.7) (thickness 0.15)) (justify left bottom))
    )
    (fp_text value "TP_1mm_SMD" (at 0 1.4) (layer "F.Fab")
        (effects (font (size 0.7 0.7) (thickness 0.15)) (justify left bottom))
    )
    (fp_text user "Author: Antmicro" (at -0.5 4) (layer "F.Fab") hide
        (effects (font (size 0.7 0.7) (thickness 0.15)) (justify left bottom))
    )
    (fp_text user "${REFERENCE}" (at -0.5 2.8) (layer "F.Fab") hide
        (effects (font (size 0.7 0.7) (thickness 0.15)) (justify left bottom))
    )
    (fp_text user "License: Apache-2.0" (at -0.5 5.2) (layer "F.Fab") hide
        (effects (font (size 0.7 0.7) (thickness 0.15)) (justify left bottom))
    )
    (fp_circle (center 0 0) (end 0.6 0)
      (stroke (width 0.05) (type default)) (fill none) (layer "F.CrtYd"))
    (pad "1" smd circle (at 0 0) (size 1 1) (layers "F.Cu" "F.Mask")
      (net 785 "Net-(U15-EN)") (pinfunction "1") (pintype "passive"))
  )
	(footprint "antmicro-footprints:TP_SMD_1mm" (layer "F.Cu")
    (at 83.95 69.6)
    (property "Author" "Antmicro")
    (property "License" "Apache-2.0")
    (property "MPN" "")
    (property "Manufacturer" "")
    (property "Sheetfile" "power-supply.kicad_sch")
    (property "Sheetname" "Power supply")
    (property "exclude_from_bom" "")
    (property "ki_description" "Test point 1mm SMD")
    (property "ki_keywords" "TESTPOINT")
    (attr exclude_from_pos_files exclude_from_bom)
    (fp_text reference "TP12" (at -1.63 1.735) (layer "F.SilkS")
        (effects (font (size 0.7 0.7) (thickness 0.15)) (justify left bottom))
    )
    (fp_text value "TP_1mm_SMD" (at 0 1.4) (layer "F.Fab")
        (effects (font (size 0.7 0.7) (thickness 0.15)) (justify left bottom))
    )
    (fp_text user "Author: Antmicro" (at -0.5 4) (layer "F.Fab") hide
        (effects (font (size 0.7 0.7) (thickness 0.15)) (justify left bottom))
    )
    (fp_text user "${REFERENCE}" (at -0.5 2.8) (layer "F.Fab") hide
        (effects (font (size 0.7 0.7) (thickness 0.15)) (justify left bottom))
    )
    (fp_text user "License: Apache-2.0" (at -0.5 5.2) (layer "F.Fab") hide
        (effects (font (size 0.7 0.7) (thickness 0.15)) (justify left bottom))
    )
    (fp_circle (center 0 0) (end 0.6 0)
      (stroke (width 0.05) (type default)) (fill none) (layer "F.CrtYd"))
    (pad "1" smd circle (at 0 0) (size 1 1) (layers "F.Cu" "F.Mask")
      (net 270 "/Power supply/5V0_PG") (pinfunction "1") (pintype "passive"))
  )
)
